(kicad_pcb
	(version 20260206)
	(generator "pcbnew")
	(generator_version "10.0")
	(general
		(thickness 1.6)
		(legacy_teardrops no)
	)
	(paper "A4")
	(title_block
		(title "v2-pdb — ms_pdb_v2.brd")
		(comment 1 "Open CloudServer (Microsoft) / footprint 327 of 348 (J10), pads 1-46 of 46")
	)
	(layers
		(0 "F.Cu" signal "TOP")
		(4 "In1.Cu" signal "GND")
		(6 "In2.Cu" signal "IN1")
		(8 "In3.Cu" signal "VCC")
		(10 "In4.Cu" signal "VCC1")
		(12 "In5.Cu" signal "IN2")
		(14 "In6.Cu" signal "GND1")
		(2 "B.Cu" signal "BOTTOM")
		(9 "F.Adhes" user "F.Adhesive")
		(11 "B.Adhes" user "B.Adhesive")
		(13 "F.Paste" user "Package Geometry/Pastemask Top")
		(15 "B.Paste" user "Package Geometry/Pastemask Bottom")
		(5 "F.SilkS" user "Ref Des/Silkscreen Top")
		(7 "B.SilkS" user "Ref Des/Silkscreen Bottom")
		(1 "F.Mask" user "Board Geometry/Soldermask Top")
		(3 "B.Mask" user "Board Geometry/Soldermask Bottom")
		(17 "Dwgs.User" user "User.Drawings")
		(19 "Cmts.User" user "User.Comments")
		(21 "Eco1.User" user "User.Eco1")
		(23 "Eco2.User" user "User.Eco2")
		(25 "Edge.Cuts" user "Board Geometry/Outline")
		(27 "Margin" user)
		(31 "F.CrtYd" user "Package Geometry/Place Bound Top")
		(29 "B.CrtYd" user "Package Geometry/Place Bound Bottom")
		(35 "F.Fab" user "Ref Des/Assembly Top")
		(33 "B.Fab" user "Ref Des/Assembly Bottom")
	)
	(footprint ""
		(layer "B.Cu")
		(at 44.040044 -141.61008 90)
		(property "Reference" "J10"
			(at 6.161024 -4.691126 0)
			(unlocked yes)
			(layer "B.SilkS")
			(effects
				(font
					(size 0.7874 0.5842)
					(thickness 0.1524)
				)
				(justify left mirror)
			)
		)
		(property "Value" ""
			(at 0 0 90)
			(layer "B.Fab")
			(effects
				(font
					(size 1.27 1.27)
				)
				(justify mirror)
			)
		)
		(duplicate_pad_numbers_are_jumpers no)
		(pad "" np_thru_hole circle
			(at -1.35001 -2.54)
			(size 2.5146 2.5146)
			(drill 2.5146)
			(layers "*.Cu" "*.Mask")
			(clearance 0.381)
			(thermal_gap 0.381)
		)
		(pad "" np_thru_hole circle
			(at 0 50.8)
			(size 2.5146 2.5146)
			(drill 2.5146)
			(layers "*.Cu" "*.Mask")
			(clearance 0.381)
			(thermal_gap 0.381)
		)
		(pad "P1" thru_hole rect
			(at 0 0)
			(size 1.1684 1.1684)
			(drill 0.762)
			(layers "*.Cu" "*.Mask")
			(remove_unused_layers no)
			(net "GND")
			(clearance 0.0508)
			(padstack
				(mode front_inner_back)
				(layer "Inner"
					(shape circle)
					(size 1.1684 1.1684)
					(clearance 0.0508)
				)
				(layer "B.Cu"
					(shape rect)
					(size 1.1684 1.1684)
					(thermal_gap 0.0508)
					(clearance 0.0508)
				)
			)
		)
		(pad "P2" thru_hole circle
			(at 0 2.54)
			(size 1.1684 1.1684)
			(drill 0.762)
			(layers "*.Cu" "*.Mask")
			(remove_unused_layers no)
			(net "GND")
			(clearance 0.0508)
			(thermal_gap 0.0508)
		)
		(pad "P3" thru_hole circle
			(at 0 5.08)
			(size 1.1684 1.1684)
			(drill 0.762)
			(layers "*.Cu" "*.Mask")
			(remove_unused_layers no)
			(net "GND")
			(clearance 0.0508)
			(thermal_gap 0.0508)
		)
		(pad "P4" thru_hole circle
			(at 0 7.62)
			(size 1.1684 1.1684)
			(drill 0.762)
			(layers "*.Cu" "*.Mask")
			(remove_unused_layers no)
			(net "GND")
			(clearance 0.0508)
			(thermal_gap 0.0508)
		)
		(pad "P5" thru_hole circle
			(at 0 10.16)
			(size 1.1684 1.1684)
			(drill 0.762)
			(layers "*.Cu" "*.Mask")
			(remove_unused_layers no)
			(net "GND")
			(clearance 0.0508)
			(thermal_gap 0.0508)
		)
		(pad "P6" thru_hole circle
			(at 0 12.7)
			(size 1.1684 1.1684)
			(drill 0.762)
			(layers "*.Cu" "*.Mask")
			(remove_unused_layers no)
			(net "GND")
			(clearance 0.0508)
			(thermal_gap 0.0508)
		)
		(pad "P7" thru_hole circle
			(at 0 15.24)
			(size 1.1684 1.1684)
			(drill 0.762)
			(layers "*.Cu" "*.Mask")
			(remove_unused_layers no)
			(net "GND")
			(clearance 0.0508)
			(thermal_gap 0.0508)
		)
		(pad "P8" thru_hole circle
			(at 0 17.78)
			(size 1.1684 1.1684)
			(drill 0.762)
			(layers "*.Cu" "*.Mask")
			(remove_unused_layers no)
			(net "GND")
			(clearance 0.0508)
			(thermal_gap 0.0508)
		)
		(pad "P9" thru_hole circle
			(at 0 20.32)
			(size 1.1684 1.1684)
			(drill 0.762)
			(layers "*.Cu" "*.Mask")
			(remove_unused_layers no)
			(net "P12V")
			(clearance 0.0508)
			(thermal_gap 0.0508)
		)
		(pad "P10" thru_hole circle
			(at 0 22.86)
			(size 1.1684 1.1684)
			(drill 0.762)
			(layers "*.Cu" "*.Mask")
			(remove_unused_layers no)
			(net "P12V")
			(clearance 0.0508)
			(thermal_gap 0.0508)
		)
		(pad "P11" thru_hole circle
			(at 0 25.4)
			(size 1.1684 1.1684)
			(drill 0.762)
			(layers "*.Cu" "*.Mask")
			(remove_unused_layers no)
			(net "P12V")
			(clearance 0.0508)
			(thermal_gap 0.0508)
		)
		(pad "P12" thru_hole circle
			(at 0 27.94)
			(size 1.1684 1.1684)
			(drill 0.762)
			(layers "*.Cu" "*.Mask")
			(remove_unused_layers no)
			(net "P12V")
			(clearance 0.0508)
			(thermal_gap 0.0508)
		)
		(pad "P13" thru_hole circle
			(at 0 30.48)
			(size 1.1684 1.1684)
			(drill 0.762)
			(layers "*.Cu" "*.Mask")
			(remove_unused_layers no)
			(net "P12V")
			(clearance 0.0508)
			(thermal_gap 0.0508)
		)
		(pad "P14" thru_hole circle
			(at 0 33.02)
			(size 1.1684 1.1684)
			(drill 0.762)
			(layers "*.Cu" "*.Mask")
			(remove_unused_layers no)
			(net "P12V")
			(clearance 0.0508)
			(thermal_gap 0.0508)
		)
		(pad "P15" thru_hole circle
			(at 0 35.56)
			(size 1.1684 1.1684)
			(drill 0.762)
			(layers "*.Cu" "*.Mask")
			(remove_unused_layers no)
			(net "P12V")
			(clearance 0.0508)
			(thermal_gap 0.0508)
		)
		(pad "P16" thru_hole circle
			(at 0 38.1)
			(size 1.1684 1.1684)
			(drill 0.762)
			(layers "*.Cu" "*.Mask")
			(remove_unused_layers no)
			(net "P12V")
			(clearance 0.0508)
			(thermal_gap 0.0508)
		)
		(pad "P17" thru_hole circle
			(at -2.70002 38.1)
			(size 1.1684 1.1684)
			(drill 0.762)
			(layers "*.Cu" "*.Mask")
			(remove_unused_layers no)
			(net "P12V")
			(clearance 0.0508)
			(thermal_gap 0.0508)
		)
		(pad "P18" thru_hole circle
			(at -2.70002 35.56)
			(size 1.1684 1.1684)
			(drill 0.762)
			(layers "*.Cu" "*.Mask")
			(remove_unused_layers no)
			(net "P12V")
			(clearance 0.0508)
			(thermal_gap 0.0508)
		)
		(pad "P19" thru_hole circle
			(at -2.70002 33.02)
			(size 1.1684 1.1684)
			(drill 0.762)
			(layers "*.Cu" "*.Mask")
			(remove_unused_layers no)
			(net "P12V")
			(clearance 0.0508)
			(thermal_gap 0.0508)
		)
		(pad "P20" thru_hole circle
			(at -2.70002 30.48)
			(size 1.1684 1.1684)
			(drill 0.762)
			(layers "*.Cu" "*.Mask")
			(remove_unused_layers no)
			(net "P12V")
			(clearance 0.0508)
			(thermal_gap 0.0508)
		)
		(pad "P21" thru_hole circle
			(at -2.70002 27.94)
			(size 1.1684 1.1684)
			(drill 0.762)
			(layers "*.Cu" "*.Mask")
			(remove_unused_layers no)
			(net "P12V")
			(clearance 0.0508)
			(thermal_gap 0.0508)
		)
		(pad "P22" thru_hole circle
			(at -2.70002 25.4)
			(size 1.1684 1.1684)
			(drill 0.762)
			(layers "*.Cu" "*.Mask")
			(remove_unused_layers no)
			(net "P12V")
			(clearance 0.0508)
			(thermal_gap 0.0508)
		)
		(pad "P23" thru_hole circle
			(at -2.70002 22.86)
			(size 1.1684 1.1684)
			(drill 0.762)
			(layers "*.Cu" "*.Mask")
			(remove_unused_layers no)
			(net "P12V")
			(clearance 0.0508)
			(thermal_gap 0.0508)
		)
		(pad "P24" thru_hole circle
			(at -2.70002 20.32)
			(size 1.1684 1.1684)
			(drill 0.762)
			(layers "*.Cu" "*.Mask")
			(remove_unused_layers no)
			(net "P12V")
			(clearance 0.0508)
			(thermal_gap 0.0508)
		)
		(pad "P25" thru_hole circle
			(at -2.70002 17.78)
			(size 1.1684 1.1684)
			(drill 0.762)
			(layers "*.Cu" "*.Mask")
			(remove_unused_layers no)
			(net "GND")
			(clearance 0.0508)
			(thermal_gap 0.0508)
		)
		(pad "P26" thru_hole circle
			(at -2.70002 15.24)
			(size 1.1684 1.1684)
			(drill 0.762)
			(layers "*.Cu" "*.Mask")
			(remove_unused_layers no)
			(net "GND")
			(clearance 0.0508)
			(thermal_gap 0.0508)
		)
		(pad "P27" thru_hole circle
			(at -2.70002 12.7)
			(size 1.1684 1.1684)
			(drill 0.762)
			(layers "*.Cu" "*.Mask")
			(remove_unused_layers no)
			(net "GND")
			(clearance 0.0508)
			(thermal_gap 0.0508)
		)
		(pad "P28" thru_hole circle
			(at -2.70002 10.16)
			(size 1.1684 1.1684)
			(drill 0.762)
			(layers "*.Cu" "*.Mask")
			(remove_unused_layers no)
			(net "GND")
			(clearance 0.0508)
			(thermal_gap 0.0508)
		)
		(pad "P29" thru_hole circle
			(at -2.70002 7.62)
			(size 1.1684 1.1684)
			(drill 0.762)
			(layers "*.Cu" "*.Mask")
			(remove_unused_layers no)
			(net "GND")
			(clearance 0.0508)
			(thermal_gap 0.0508)
		)
		(pad "P30" thru_hole circle
			(at -2.70002 5.08)
			(size 1.1684 1.1684)
			(drill 0.762)
			(layers "*.Cu" "*.Mask")
			(remove_unused_layers no)
			(net "GND")
			(clearance 0.0508)
			(thermal_gap 0.0508)
		)
		(pad "P31" thru_hole circle
			(at -2.70002 2.54)
			(size 1.1684 1.1684)
			(drill 0.762)
			(layers "*.Cu" "*.Mask")
			(remove_unused_layers no)
			(net "GND")
			(clearance 0.0508)
			(thermal_gap 0.0508)
		)
		(pad "P32" thru_hole circle
			(at -2.70002 0)
			(size 1.1684 1.1684)
			(drill 0.762)
			(layers "*.Cu" "*.Mask")
			(remove_unused_layers no)
			(net "GND")
			(clearance 0.0508)
			(thermal_gap 0.0508)
		)
		(pad "S1" thru_hole circle
			(at 0.55499 41.60012)
			(size 1.1684 1.1684)
			(drill 0.762)
			(layers "*.Cu" "*.Mask")
			(remove_unused_layers no)
			(net "T4_BLAD1_TXD")
			(clearance 0.0508)
			(thermal_gap 0.0508)
		)
		(pad "S2" thru_hole circle
			(at -0.71501 42.87012)
			(size 1.1684 1.1684)
			(drill 0.762)
			(layers "*.Cu" "*.Mask")
			(remove_unused_layers no)
			(net "T4_BLAD1_RXD")
			(clearance 0.0508)
			(thermal_gap 0.0508)
		)
		(pad "S3" thru_hole circle
			(at 0.55499 44.14012)
			(size 1.1684 1.1684)
			(drill 0.762)
			(layers "*.Cu" "*.Mask")
			(remove_unused_layers no)
			(net "T4_BLAD1_EN")
			(clearance 0.0508)
			(thermal_gap 0.0508)
		)
		(pad "S4" thru_hole circle
			(at -0.71501 45.41012)
			(size 1.1684 1.1684)
			(drill 0.762)
			(layers "*.Cu" "*.Mask")
			(remove_unused_layers no)
			(net "B7_PSU_ALERT_N")
			(clearance 0.0508)
			(thermal_gap 0.0508)
		)
		(pad "S5" thru_hole circle
			(at 0.55499 46.68012)
			(size 1.1684 1.1684)
			(drill 0.762)
			(layers "*.Cu" "*.Mask")
			(remove_unused_layers no)
			(net "T4_BLAD2_TXD")
			(clearance 0.0508)
			(thermal_gap 0.0508)
		)
		(pad "S6" thru_hole circle
			(at -0.71501 47.95012)
			(size 1.1684 1.1684)
			(drill 0.762)
			(layers "*.Cu" "*.Mask")
			(remove_unused_layers no)
			(net "T4_BLAD2_RXD")
			(clearance 0.0508)
			(thermal_gap 0.0508)
		)
		(pad "S7" thru_hole circle
			(at -3.25501 47.95012)
			(size 1.1684 1.1684)
			(drill 0.762)
			(layers "*.Cu" "*.Mask")
			(remove_unused_layers no)
			(net "T4_BLAD4_RXD")
			(clearance 0.0508)
			(thermal_gap 0.0508)
		)
		(pad "S8" thru_hole circle
			(at -1.98501 46.68012)
			(size 1.1684 1.1684)
			(drill 0.762)
			(layers "*.Cu" "*.Mask")
			(remove_unused_layers no)
			(net "T4_BLAD4_TXD")
			(clearance 0.0508)
			(thermal_gap 0.0508)
		)
		(pad "S9" thru_hole circle
			(at -3.25501 45.41012)
			(size 1.1684 1.1684)
			(drill 0.762)
			(layers "*.Cu" "*.Mask")
			(remove_unused_layers no)
			(net "B8_PSU_ALERT_N")
			(clearance 0.0508)
			(thermal_gap 0.0508)
		)
		(pad "S10" thru_hole circle
			(at -1.98501 44.14012)
			(size 1.1684 1.1684)
			(drill 0.762)
			(layers "*.Cu" "*.Mask")
			(remove_unused_layers no)
			(net "T4_BLAD3_EN")
			(clearance 0.0508)
			(thermal_gap 0.0508)
		)
		(pad "S11" thru_hole circle
			(at -3.25501 42.87012)
			(size 1.1684 1.1684)
			(drill 0.762)
			(layers "*.Cu" "*.Mask")
			(remove_unused_layers no)
			(net "T4_BLAD3_RXD")
			(clearance 0.0508)
			(thermal_gap 0.0508)
		)
		(pad "S12" thru_hole circle
			(at -1.98501 41.60012)
			(size 1.1684 1.1684)
			(drill 0.762)
			(layers "*.Cu" "*.Mask")
			(remove_unused_layers no)
			(net "T4_BLAD3_TXD")
			(clearance 0.0508)
			(thermal_gap 0.0508)
		)
	)
)
